# BASEBOARD_FAB2 (Tioga Pass) — schematic parts with pin connectivity, parts 160–331 of 4751; source: Cadence DE-HDL packaged netlist (pstxprt.dat, pstxnet.dat, pstchip.dat)

C1L10  CAP_A  1.0UF 6.3V 10% X6S  pkg 0402V  page 175 : 1 = FP_RST_BTN_R_N ; 2 = GND
C1L11  CAP_A  0.1UF 16V 10% X7R  pkg 0402V  page 111 : 1 = P3V3_STBY ; 2 = GND
C1L16  CAP_A  0.1UF 16V 10% X7R  pkg 0402V  page 196 : 1 = P3V3 ; 2 = GND
C1L17  CAP_A  0.1UF 16V 10% X7R  pkg 0402V  page 175 : 1 = P3V3_STBY ; 2 = GND
C1L18  CAP_A  1.0UF 6.3V 10% X6S  pkg 0402V  page 175 : 1 = FP_PWR_BTN_R1_N ; 2 = GND
C1L19  CAP  1.0UF 16V 10% X6S  pkg 0402  page 112 : 1 = P3V3_STBY ; 2 = GND
C1L20  CAP_A  0.01UF 25V 10% X7R  pkg 0402V  page 113 : 1 = P3V3_STBY ; 2 = GND
C1L119  CAP  1.0UF 16V 10% X6S  pkg 0402  page 189 : 1 = P3V3_STBY ; 2 = GND
C1M3  CAP_A  1.0UF 6.3V 10% X6S  pkg 0402V  page 177 : 1 = P3V3 ; 2 = GND
C1M4  CAP  47.0PF 50V 5% EMPTY  pkg 0402LF  page 167 : 1 = ISENSE_TMP421_1_DXP ; 2 = ISENSE_TMP421_1_DXN
C1M5  CAPP  68UF 16V 20% TANT  pkg 3018  page 195 : 1 = P12V_STBY ; 2 = GND
C1M6  CAP  0.22UF 16V 10% X7R  pkg 0402  page 106 : 1 = P3E_CPU0_PE3_OCP_TXP<15> ; 2 = P3E_OCP_CPU0_PE3_C_TXP<15>
C1M7  CAP  0.22UF 16V 10% X7R  pkg 0402  page 106 : 1 = P3E_CPU0_PE3_OCP_TXN<15> ; 2 = P3E_OCP_CPU0_PE3_C_TXN<15>
C1M8  CAP  0.22UF 16V 10% X7R  pkg 0402  page 106 : 1 = P3E_CPU0_PE3_OCP_TXP<14> ; 2 = P3E_OCP_CPU0_PE3_C_TXP<14>
C1M9  CAP  0.22UF 16V 10% X7R  pkg 0402  page 106 : 1 = P3E_CPU0_PE3_OCP_TXN<14> ; 2 = P3E_OCP_CPU0_PE3_C_TXN<14>
C1M10  CAP  0.22UF 16V 10% X7R  pkg 0402  page 106 : 1 = P3E_CPU0_PE3_OCP_TXP<13> ; 2 = P3E_OCP_CPU0_PE3_C_TXP<13>
C1M11  CAP  0.22UF 16V 10% X7R  pkg 0402  page 106 : 1 = P3E_CPU0_PE3_OCP_TXN<13> ; 2 = P3E_OCP_CPU0_PE3_C_TXN<13>
C1M12  CAP  0.22UF 16V 10% X7R  pkg 0402  page 106 : 1 = P3E_CPU0_PE3_OCP_TXP<12> ; 2 = P3E_OCP_CPU0_PE3_C_TXP<12>
C1M13  CAP  0.22UF 16V 10% X7R  pkg 0402  page 106 : 1 = P3E_CPU0_PE3_OCP_TXN<12> ; 2 = P3E_OCP_CPU0_PE3_C_TXN<12>
C1M14  CAP  0.22UF 16V 10% X7R  pkg 0402  page 106 : 1 = P3E_CPU0_PE3_OCP_TXP<11> ; 2 = P3E_OCP_CPU0_PE3_C_TXP<11>
C1M15  CAP  0.22UF 16V 10% X7R  pkg 0402  page 106 : 1 = P3E_CPU0_PE3_OCP_TXN<11> ; 2 = P3E_OCP_CPU0_PE3_C_TXN<11>
C1M16  CAP  0.22UF 16V 10% X7R  pkg 0402  page 106 : 1 = P3E_CPU0_PE3_OCP_TXP<10> ; 2 = P3E_OCP_CPU0_PE3_C_TXP<10>
C1M17  CAP  0.22UF 16V 10% X7R  pkg 0402  page 106 : 1 = P3E_CPU0_PE3_OCP_TXN<10> ; 2 = P3E_OCP_CPU0_PE3_C_TXN<10>
C1M18  CAP  0.22UF 16V 10% X7R  pkg 0402  page 106 : 1 = P3E_CPU0_PE3_OCP_TXP<9> ; 2 = P3E_OCP_CPU0_PE3_C_TXP<9>
C1M19  CAP  0.22UF 16V 10% X7R  pkg 0402  page 106 : 1 = P3E_CPU0_PE3_OCP_TXN<9> ; 2 = P3E_OCP_CPU0_PE3_C_TXN<9>
C1M20  CAP_A  0.1UF 16V 10% X7R  pkg 0402V  page 186 : 1 = P3V3_STBY ; 2 = GND
C1M21  CAP_A  1.0UF 6.3V 10% X6S  pkg 0402V  page 186 : 1 = P3V3 ; 2 = GND
C1M22  CAP_A  0.1UF 16V 10% X7R  pkg 0402V  page 186 : 1 = P12V_STBY ; 2 = GND
C1M23  CAP_A  0.1UF 16V 10% X7R  pkg 0402V  page 186 : 1 = P12V_STBY ; 2 = GND
C1M24  CAP_A  0.1UF 16V 10% X7R  pkg 0402V  page 186 : 1 = P3V3 ; 2 = GND
C1M25  CAP_A  1.0UF 6.3V 10% X6S  pkg 0402V  page 186 : 1 = P3V3_STBY ; 2 = GND
C1M26  CAP  10UF 16V 10% X6S  pkg 0805  page 186 : 1 = P12V_STBY ; 2 = GND
C1M27  CAP  10UF 16V 10% X6S  pkg 0805  page 186 : 1 = P12V_STBY ; 2 = GND
C1M28  CAP_A  0.01UF 25V 10% X7R  pkg 0402V  page 113 : 1 = P3V3_STBY ; 2 = GND
C1M29  CAP_A  0.1UF 16V 10% X7R  pkg 0402V  page 113 : 1 = P1V8_MCP_CPU0 ; 2 = GND
C1M30  CAP_A  0.01UF 25V 10% X7R  pkg 0402V  page 112 : 1 = P3V3_STBY ; 2 = GND
C1M31  CAP_A  0.01UF 25V 10% X7R  pkg 0402V  page 113 : 1 = P3V3_STBY ; 2 = GND
C1M32  CAP_A  1.0UF 6.3V 10% X6S  pkg 0402V  page 113 : 1 = P3V3_STBY ; 2 = GND
C1M33  CAP_A  0.1UF 16V 10% X7R  pkg 0402V  page 113 : 1 = JTAG_MCP_TMS_R1 ; 2 = GND
C1M34  CAP_A  0.01UF 25V 10% X7R  pkg 0402V  page 113 : 1 = P3V3_STBY ; 2 = GND
C1M35  CAP_A  0.01UF 25V 10% X7R  pkg 0402V  page 113 : 1 = P3V3_STBY ; 2 = GND
C1M36  CAP_A  0.01UF 25V 10% X7R  pkg 0402V  page 112 : 1 = P3V3_STBY ; 2 = GND
C1M37  CAP_A  1.0UF 6.3V 10% X6S  pkg 0402V  page 112 : 1 = P3V3_STBY ; 2 = GND
C1M38  CAP_A  0.1UF 16V 10% X7R  pkg 0402V  page 176 : 1 = P5V_TPS2061 ; 2 = GND
C1R1  CAP  0.22UF 16V 10% X7R  pkg 0402  page 106 : 1 = P3E_CPU0_PE3_OCP_TXN<0> ; 2 = P3E_OCP_CPU0_PE3_C_TXN<0>
C1R2  CAP  0.22UF 16V 10% X7R  pkg 0402  page 106 : 1 = P3E_CPU0_PE3_OCP_TXP<0> ; 2 = P3E_OCP_CPU0_PE3_C_TXP<0>
C1R3  CAP  0.22UF 16V 10% X7R  pkg 0402  page 106 : 1 = P3E_CPU0_PE3_OCP_TXN<1> ; 2 = P3E_OCP_CPU0_PE3_C_TXN<1>
C1R4  CAP  0.22UF 16V 10% X7R  pkg 0402  page 106 : 1 = P3E_CPU0_PE3_OCP_TXP<1> ; 2 = P3E_OCP_CPU0_PE3_C_TXP<1>
C1R5  CAP  0.22UF 16V 10% X7R  pkg 0402  page 106 : 1 = P3E_CPU0_PE3_OCP_TXN<2> ; 2 = P3E_OCP_CPU0_PE3_C_TXN<2>
C1R6  CAP  0.22UF 16V 10% X7R  pkg 0402  page 106 : 1 = P3E_CPU0_PE3_OCP_TXP<2> ; 2 = P3E_OCP_CPU0_PE3_C_TXP<2>
C1R7  CAP  0.22UF 16V 10% X7R  pkg 0402  page 106 : 1 = P3E_CPU0_PE3_OCP_TXN<3> ; 2 = P3E_OCP_CPU0_PE3_C_TXN<3>
C1R8  CAP  0.22UF 16V 10% X7R  pkg 0402  page 106 : 1 = P3E_CPU0_PE3_OCP_TXP<3> ; 2 = P3E_OCP_CPU0_PE3_C_TXP<3>
C1R9  CAP  0.22UF 16V 10% X7R  pkg 0402  page 106 : 1 = P3E_CPU0_PE3_OCP_TXN<4> ; 2 = P3E_OCP_CPU0_PE3_C_TXN<4>
C1R10  CAP  0.22UF 16V 10% X7R  pkg 0402  page 106 : 1 = P3E_CPU0_PE3_OCP_TXP<4> ; 2 = P3E_OCP_CPU0_PE3_C_TXP<4>
C1R13  CAP  10UF 6.3V 20% X6S  pkg 0603  page 139 : 1 = P3V3_STBY ; 2 = GND
C1R14  CAP_A  0.1UF 16V 10% X7R  pkg 0402V  page 139 : 1 = P3V3_STBY ; 2 = GND
C1R15  CAP_A  0.1UF 16V 10% X7R  pkg 0402V  page 139 : 1 = P0V9_LAN ; 2 = GND
C1R16  CAP  10UF 6.3V 20% X6S  pkg 0603  page 139 : 1 = P0V9_LAN ; 2 = GND
C1R17  CAP  10UF 6.3V 20% X6S  pkg 0603  page 139 : 1 = P1V5_LAN ; 2 = GND
C1R18  CAP_A  0.1UF 16V 10% X7R  pkg 0402V  page 139 : 1 = P0V9_LAN ; 2 = GND
C1R19  CAP_A  0.1UF 16V 10% X7R  pkg 0402V  page 139 : 1 = P1V5_LAN ; 2 = GND
C1R20  CAP_A  0.1UF 16V 10% X7R  pkg 0402V  page 139 : 1 = P3V3_STBY ; 2 = GND
C1R21  CAP_A  0.1UF 16V 10% X7R  pkg 0402V  page 139 : 1 = P3V3_STBY ; 2 = GND
C1R22  CAP  10UF 6.3V 20% X6S  pkg 0603  page 139 : 1 = P3V3_STBY ; 2 = GND
C1R23  CAPP  68UF 16V 20% TANT  pkg 3018  page 195 : 1 = P12V_STBY ; 2 = GND
C1R24  CAP_A  0.1UF 16V 10% X7R  pkg 0402V  page 139 : 1 = P0V9_LAN ; 2 = GND
C1R25  CAP_A  0.1UF 16V 10% X7R  pkg 0402V  page 140 : 1 = P3V3_STBY ; 2 = GND
C1R26  CAP_A  0.1UF 16V 10% X7R  pkg 0402V  page 139 : 1 = P1V5_LAN ; 2 = GND
C1R27  CAP_A  0.1UF 16V 10% X7R  pkg 0402V  page 170 : 1 = P3V3_STBY ; 2 = GND
C1R28  CAP_A  0.1UF 16V 10% X7R  pkg 0402V  page 170 : 1 = P3V3_STBY ; 2 = GND
C1R29  CAP_A  0.1UF 16V 10% X7R  pkg 0402V  page 139 : 1 = P1V5_LAN ; 2 = GND
C1R30  CAP  10UF 6.3V 20% X6S  pkg 0603  page 139 : 1 = P1V5_LAN ; 2 = GND
C1R31  CAP_A  0.1UF 16V 10% X7R  pkg 0402V  page 139 : 1 = P1V5_LAN ; 2 = GND
C1T3  CAP_A  0.1UF 16V 10% X7R  pkg 0402V  page 139 : 1 = P3V3_STBY ; 2 = GND
C1T4  CAP  10UF 6.3V 20% X6S  pkg 0603  page 139 : 1 = P0V9_LAN ; 2 = GND
C1T5  CAP_A  0.1UF 16V 10% X7R  pkg 0402V  page 139 : 1 = P0V9_LAN ; 2 = GND
C1T7  CAP  10UF 6.3V 20% X6S  pkg 0603  page 239 : 1 = P3V3_STBY ; 2 = GND
C1T10  CAP_A  0.1UF 16V 10% X7R  pkg 0402V  page 158 : 1 = P3V3_STBY ; 2 = GND
C1T11  CAP_A  0.1UF 16V 10% X7R  pkg 0402V  page 158 : 1 = P3V3_STBY ; 2 = GND
C1T15  CAP  10UF 6.3V 20% X6S  pkg 0603  page 239 : 1 = P1V2_AUX_BMC ; 2 = GND
C1T21  CAP_A  1.0UF 6.3V 10% X6S  pkg 0402V  page 148 : 1 = PVCCIO_CPU0 ; 2 = GND
C1T56  CAP_A  0.1UF 16V 10% X7R  pkg 0402V  page 155 : 1 = P3V3_STBY ; 2 = GND
C1U19  CAP  1.0UF 16V 10% X6S  pkg 0402  page 152 : 1 = P3V3 ; 2 = GND
C1U21  CAP  47.0PF 50V 5% COG  pkg 0402LF  page 169 : 1 = A_P1V05_STBY_PCH_SENSOR ; 2 = GND
C1U22  CAP_A  0.1UF 16V 10% X7R  pkg 0402V  page 152 : 1 = P0V7_GTL2014_2 ; 2 = GND
C1W7  CAP  10UF 6.3V 20% X6S  pkg 0603  page 239 : 1 = P3V3_STBY ; 2 = GND
C1W15  CAP  10UF 6.3V 20% X6S  pkg 0603  page 239 : 1 = P2V5_AUX_BMC ; 2 = GND
C1W16  CAP  1000PF 50V 10% X7R  pkg 0402LF  page 199 : 1 = A_HSC_TEMP ; 2 = GND
C1W17  CAP  10UF 16V 10% EMPTY  pkg 0805  page 101 : 1 = P3V3_STBY_MNG_RMII ; 2 = GND
C1W18  CAP_A  0.1UF 16V 10% X7R  pkg 0402V  page 176 : 1 = P3V3_STBY ; 2 = GND
C1W19  CAP_A  0.1UF 16V 10% X7R  pkg 0402V  page 176 : 1 = P3V3_STBY ; 2 = GND
C1W20  CAP  0.22UF 16V 10% X7R  pkg 0402  page 151 : 1 = BMC_M_CLK ; 2 = GND
C1W21  CAP  0.033UF 50V 10% X7R  pkg 0603LF  page 146 : 1 = A_USB2AVRES ; 2 = GND
C2A1  CAP_A  47UF 4V 20% X5R  pkg 0603V  page 228 : 1 = PVDDQ_KLM ; 2 = GND
C2A2  CAP_A  47UF 4V 20% X5R  pkg 0603V  page 228 : 1 = PVDDQ_KLM ; 2 = GND
C2A3  CAP_A  47UF 4V 20% X5R  pkg 0603V  page 228 : 1 = PVDDQ_KLM ; 2 = GND
C2A4  CAP_A  47UF 4V 20% X5R  pkg 0603V  page 228 : 1 = PVDDQ_KLM ; 2 = GND
C2A5  CAP_A  47UF 4V 20% X5R  pkg 0603V  page 228 : 1 = PVDDQ_KLM ; 2 = GND
C2A6  CAP_A  47UF 4V 20% X5R  pkg 0603V  page 228 : 1 = PVDDQ_KLM ; 2 = GND
C2A7  CAP_A  47UF 4V 20% X5R  pkg 0603V  page 228 : 1 = PVDDQ_KLM ; 2 = GND
C2A8  CAP  100UF 4V 20% X5R  pkg 0805  page 228 : 1 = PVDDQ_KLM ; 2 = GND
C2A9  CAP_A  47UF 4V 20% X5R  pkg 0603V  page 228 : 1 = PVDDQ_KLM ; 2 = GND
C2A10  CAP_A  47UF 4V 20% X5R  pkg 0603V  page 228 : 1 = PVDDQ_KLM ; 2 = GND
C2A11  CAP_A  47UF 4V 20% X5R  pkg 0603V  page 228 : 1 = PVDDQ_KLM ; 2 = GND
C2A12  CAP_A  47UF 4V 20% X5R  pkg 0603V  page 228 : 1 = PVDDQ_KLM ; 2 = GND
C2A13  CAP_A  47UF 4V 20% X5R  pkg 0603V  page 228 : 1 = PVDDQ_KLM ; 2 = GND
C2A14  CAP_A  47UF 4V 20% X5R  pkg 0603V  page 228 : 1 = PVDDQ_KLM ; 2 = GND
C2A15  CAP_A  47UF 4V 20% X5R  pkg 0603V  page 228 : 1 = PVDDQ_KLM ; 2 = GND
C2A16  CAP  100UF 4V 20% X5R  pkg 0805  page 228 : 1 = PVDDQ_KLM ; 2 = GND
C2B1  CAP_A  47UF 4V 20% X5R  pkg 0603V  page 228 : 1 = PVDDQ_KLM ; 2 = GND
C2B2  CAP_A  47UF 4V 20% X5R  pkg 0603V  page 228 : 1 = PVDDQ_KLM ; 2 = GND
C2D1  CAP_A  22.0UF 4V 20% X6S  pkg 0603V  page 228 : 1 = PVDDQ_KLM ; 2 = GND
C2D2  CAP_A  22.0UF 4V 20% X6S  pkg 0603V  page 228 : 1 = PVDDQ_KLM ; 2 = GND
C2D3  CAP_A  22.0UF 4V 20% X6S  pkg 0603V  page 228 : 1 = PVDDQ_KLM ; 2 = GND
C2D4  CAP_A  22.0UF 4V 20% X6S  pkg 0603V  page 228 : 1 = PVDDQ_KLM ; 2 = GND
C2D5  CAP_A  22.0UF 4V 20% X6S  pkg 0603V  page 228 : 1 = PVDDQ_KLM ; 2 = GND
C2D6  CAP_A  22.0UF 4V 20% X6S  pkg 0603V  page 228 : 1 = PVDDQ_KLM ; 2 = GND
C2D7  CAP_A  22.0UF 4V 20% X6S  pkg 0603V  page 228 : 1 = PVDDQ_KLM ; 2 = GND
C2D8  CAP  10UF 4V 20% X6S  pkg 0603LF  page 76 : 1 = PVSA_CPU1 ; 2 = GND
C2D9  CAP  10UF 4V 20% X6S  pkg 0603LF  page 76 : 1 = PVSA_CPU1 ; 2 = GND
C2D10  CAP  10UF 4V 20% X6S  pkg 0603LF  page 76 : 1 = PVSA_CPU1 ; 2 = GND
C2D11  CAP  10UF 4V 20% X6S  pkg 0603LF  page 76 : 1 = PVSA_CPU1 ; 2 = GND
C2D12  CAP_A  22.0UF 4V 20% X6S  pkg 0603V  page 76 : 1 = PVCCIN_CPU1 ; 2 = GND
C2D13  CAP_A  22.0UF 4V 20% X6S  pkg 0603V  page 76 : 1 = PVCCIN_CPU1 ; 2 = GND
C2D14  CAP_A  22.0UF 4V 20% X6S  pkg 0603V  page 76 : 1 = PVCCIN_CPU1 ; 2 = GND
C2D15  CAP_A  22.0UF 4V 20% X6S  pkg 0603V  page 76 : 1 = PVCCIN_CPU1 ; 2 = GND
C2D16  CAP_A  22.0UF 4V 20% X6S  pkg 0603V  page 76 : 1 = PVCCIN_CPU1 ; 2 = GND
C2D17  CAP_A  22.0UF 4V 20% X6S  pkg 0603V  page 76 : 1 = PVCCIN_CPU1 ; 2 = GND
C2D18  CAP_A  22.0UF 4V 20% X6S  pkg 0603V  page 76 : 1 = PVCCMCP_CPU1 ; 2 = GND
C2D19  CAP_A  22.0UF 4V 20% X6S  pkg 0603V  page 76 : 1 = PVCCIN_CPU1 ; 2 = GND
C2D20  CAP_A  22.0UF 4V 20% X6S  pkg 0603V  page 76 : 1 = PVCCIN_CPU1 ; 2 = GND
C2D21  CAP_A  22.0UF 4V 20% X6S  pkg 0603V  page 76 : 1 = PVCCIN_CPU1 ; 2 = GND
C2D22  CAP_A  22.0UF 4V 20% X6S  pkg 0603V  page 76 : 1 = PVCCIN_CPU1 ; 2 = GND
C2D23  CAP_A  22.0UF 4V 20% X6S  pkg 0603V  page 76 : 1 = PVCCIN_CPU1 ; 2 = GND
C2D24  CAP_A  22.0UF 4V 20% X6S  pkg 0603V  page 76 : 1 = PVCCIN_CPU1 ; 2 = GND
C2D25  CAP_A  22.0UF 4V 20% X6S  pkg 0603V  page 76 : 1 = PVCCIN_CPU1 ; 2 = GND
C2D26  CAP_A  22.0UF 4V 20% X6S  pkg 0603V  page 76 : 1 = PVCCIN_CPU1 ; 2 = GND
C2D27  CAP_A  22.0UF 4V 20% X6S  pkg 0603V  page 76 : 1 = PVCCIN_CPU1 ; 2 = GND
C2D28  CAP_A  22.0UF 4V 20% X6S  pkg 0603V  page 76 : 1 = PVCCMCP_CPU1 ; 2 = GND
C2D29  CAP_A  22.0UF 4V 20% X6S  pkg 0603V  page 76 : 1 = PVCCMCP_CPU1 ; 2 = GND
C2D30  CAP_A  22.0UF 4V 20% X6S  pkg 0603V  page 76 : 1 = PVCCIN_CPU1 ; 2 = GND
C2D31  CAP_A  22.0UF 4V 20% X6S  pkg 0603V  page 76 : 1 = PVCCIN_CPU1 ; 2 = GND
C2D32  CAP_A  22.0UF 4V 20% X6S  pkg 0603V  page 76 : 1 = PVCCIN_CPU1 ; 2 = GND
C2D33  CAP_A  22.0UF 4V 20% X6S  pkg 0603V  page 76 : 1 = PVCCIN_CPU1 ; 2 = GND
C2D34  CAP_A  22.0UF 4V 20% X6S  pkg 0603V  page 76 : 1 = PVCCIN_CPU1 ; 2 = GND
C2D35  CAP_A  22.0UF 4V 20% X6S  pkg 0603V  page 76 : 1 = PVCCIN_CPU1 ; 2 = GND
C2D36  CAP_A  22.0UF 4V 20% X6S  pkg 0603V  page 76 : 1 = PVCCIN_CPU1 ; 2 = GND
C2D37  CAP_A  22.0UF 4V 20% X6S  pkg 0603V  page 76 : 1 = PVCCIN_CPU1 ; 2 = GND
C2D38  CAP_A  22.0UF 4V 20% X6S  pkg 0603V  page 76 : 1 = PVCCIN_CPU1 ; 2 = GND
C2D39  CAP_A  22.0UF 4V 20% X6S  pkg 0603V  page 76 : 1 = PVCCMCP_CPU1 ; 2 = GND
C2D40  CAP_A  22.0UF 4V 20% X6S  pkg 0603V  page 76 : 1 = PVCCMCP_CPU1 ; 2 = GND
C2D41  CAP_A  22.0UF 4V 20% X6S  pkg 0603V  page 225 : 1 = PVDDQ_GHJ ; 2 = GND
C2D42  CAP_A  22.0UF 4V 20% X6S  pkg 0603V  page 225 : 1 = PVDDQ_GHJ ; 2 = GND
C2D43  CAP_A  22.0UF 4V 20% X6S  pkg 0603V  page 225 : 1 = PVDDQ_GHJ ; 2 = GND
C2D44  CAP_A  22.0UF 4V 20% X6S  pkg 0603V  page 225 : 1 = PVDDQ_GHJ ; 2 = GND
C2D45  CAP_A  22.0UF 4V 20% X6S  pkg 0603V  page 225 : 1 = PVDDQ_GHJ ; 2 = GND
C2D46  CAP_A  22.0UF 4V 20% X6S  pkg 0603V  page 225 : 1 = PVDDQ_GHJ ; 2 = GND
C2D47  CAP_A  22.0UF 4V 20% X6S  pkg 0603V  page 225 : 1 = PVDDQ_GHJ ; 2 = GND
C2F1  CAP_A  47UF 4V 20% X5R  pkg 0603V  page 225 : 1 = PVDDQ_GHJ ; 2 = GND
C2F2  CAP_A  47UF 4V 20% X5R  pkg 0603V  page 229 : 1 = PVTT_GHJ ; 2 = GND
C2G1  CAP_A  47UF 4V 20% X5R  pkg 0603V  page 225 : 1 = PVDDQ_GHJ ; 2 = GND
C2G2  CAP_A  47UF 4V 20% X5R  pkg 0603V  page 225 : 1 = PVDDQ_GHJ ; 2 = GND
C2G3  CAP_A  47UF 4V 20% X5R  pkg 0603V  page 225 : 1 = PVDDQ_GHJ ; 2 = GND
C2G4  CAP_A  47UF 4V 20% X5R  pkg 0603V  page 225 : 1 = PVDDQ_GHJ ; 2 = GND
C2G5  CAP_A  47UF 4V 20% X5R  pkg 0603V  page 225 : 1 = PVDDQ_GHJ ; 2 = GND
C2G6  CAP_A  47UF 4V 20% X5R  pkg 0603V  page 225 : 1 = PVDDQ_GHJ ; 2 = GND
C2G7  CAP  100UF 4V 20% X5R  pkg 0805  page 225 : 1 = PVDDQ_GHJ ; 2 = GND
C2G8  CAP_A  47UF 4V 20% X5R  pkg 0603V  page 225 : 1 = PVDDQ_GHJ ; 2 = GND
C2G9  CAP_A  47UF 4V 20% X5R  pkg 0603V  page 225 : 1 = PVDDQ_GHJ ; 2 = GND
C2G10  CAP_A  47UF 4V 20% X5R  pkg 0603V  page 225 : 1 = PVDDQ_GHJ ; 2 = GND
C2G11  CAP_A  47UF 4V 20% X5R  pkg 0603V  page 225 : 1 = PVDDQ_GHJ ; 2 = GND
C2G12  CAP_A  47UF 4V 20% X5R  pkg 0603V  page 225 : 1 = PVDDQ_GHJ ; 2 = GND
